# T6G (Grand Teton) — schematic netlist excerpt (pin names and nets, part order shuffled) for the footprints in the layout excerpt that follows; sources: Cadence DE-HDL packaged netlist, KiCad conversion of 04192023_DAF0TMB3IC0_F0TG_MB_C_brd_V02_OCP.brd

C2609  Q_CAP  22UF 4V 20% X6S  pkg C0402  page 70 : A = PVDD11_S3_P0 ; B = GND
R6147  Q_RES  1K 1% EMPTY  pkg 0402LF  page 84 : A = P1V8_AUX ; B = FAB_BMC_REV_ID1
PC106_2  Q_CAP  22UF 4V 20% X6S  pkg C0805  page 201 : A = PVDDCR_CPU1_P0 ; B = GND

(kicad_pcb
	(version 20260206)
	(generator "pcbnew")
	(generator_version "10.0")
	(general
		(thickness 1.6)
		(legacy_teardrops no)
	)
	(paper "A4")
	(title_block
		(title "04192023_DAF0TMB3IC0_F0TG_MB_C_brd_V02_OCP.brd")
		(comment 1 "Grand Teton / footprints 6838-6840 of 8354")
	)
	(layers
		(0 "F.Cu" signal "TOP")
		(4 "In1.Cu" signal "GND")
		(6 "In2.Cu" signal "IN1")
		(8 "In3.Cu" signal "GND1")
		(10 "In4.Cu" signal "IN2")
		(12 "In5.Cu" signal "GND2")
		(14 "In6.Cu" signal "IN3")
		(16 "In7.Cu" signal "GND3")
		(18 "In8.Cu" signal "VCC")
		(20 "In9.Cu" signal "VCC1")
		(22 "In10.Cu" signal "GND4")
		(24 "In11.Cu" signal "IN4")
		(26 "In12.Cu" signal "GND5")
		(28 "In13.Cu" signal "IN5")
		(30 "In14.Cu" signal "GND6")
		(32 "In15.Cu" signal "IN6")
		(34 "In16.Cu" signal "GND7")
		(2 "B.Cu" signal "BOTTOM")
		(9 "F.Adhes" user "F.Adhesive")
		(11 "B.Adhes" user "B.Adhesive")
		(13 "F.Paste" user "Package Geometry/Pastemask Top")
		(15 "B.Paste" user "Package Geometry/Pastemask Bottom")
		(5 "F.SilkS" user "Ref Des/Silkscreen Top")
		(7 "B.SilkS" user "Ref Des/Silkscreen Bottom")
		(1 "F.Mask" user "Board Geometry/Soldermask Top")
		(3 "B.Mask" user "Board Geometry/Soldermask Bottom")
		(17 "Dwgs.User" user "User.Drawings")
		(19 "Cmts.User" user "User.Comments")
		(21 "Eco1.User" user "User.Eco1")
		(23 "Eco2.User" user "User.Eco2")
		(25 "Edge.Cuts" user "Board Geometry/Outline")
		(27 "Margin" user)
		(31 "F.CrtYd" user "Package Geometry/Place Bound Top")
		(29 "B.CrtYd" user "Package Geometry/Place Bound Bottom")
		(35 "F.Fab" user "Ref Des/Assembly Top")
		(33 "B.Fab" user "Ref Des/Assembly Bottom")
	)
	(footprint ""
		(layer "B.Cu")
		(at 356.567232 -261.747762 90)
		(property "Reference" "C2609"
			(at 0 0 90)
			(layer "B.SilkS")
			(hide yes)
			(effects
				(font
					(size 1.27 1.27)
				)
				(justify mirror)
			)
		)
		(property "Value" ""
			(at 0 0 90)
			(layer "B.Fab")
			(effects
				(font
					(size 1.27 1.27)
				)
				(justify mirror)
			)
		)
		(duplicate_pad_numbers_are_jumpers no)
		(fp_line
			(start 0.7874 -0.4064)
			(end -0.7874 -0.4064)
			(stroke
				(width 0.1524)
				(type default)
			)
			(layer "B.SilkS")
		)
		(fp_line
			(start -0.7874 -0.4064)
			(end -0.7874 0.4064)
			(stroke
				(width 0.1524)
				(type default)
			)
			(layer "B.SilkS")
		)
		(fp_line
			(start 0.7874 0.4064)
			(end 0.7874 -0.4064)
			(stroke
				(width 0.1524)
				(type default)
			)
			(layer "B.SilkS")
		)
		(fp_line
			(start -0.7874 0.4064)
			(end 0.7874 0.4064)
			(stroke
				(width 0.1524)
				(type default)
			)
			(layer "B.SilkS")
		)
		(fp_line
			(start 0.67945 -0.305054)
			(end 0.12065 -0.305054)
			(stroke
				(width 0.1)
				(type default)
			)
			(layer "B.Fab")
		)
		(fp_line
			(start 0.12065 -0.305054)
			(end 0.12065 -0.2794)
			(stroke
				(width 0.1)
				(type default)
			)
			(layer "B.Fab")
		)
		(fp_line
			(start -0.12065 -0.3048)
			(end -0.67945 -0.3048)
			(stroke
				(width 0.1)
				(type default)
			)
			(layer "B.Fab")
		)
		(fp_line
			(start -0.67945 -0.3048)
			(end -0.67945 0.3048)
			(stroke
				(width 0.1)
				(type default)
			)
			(layer "B.Fab")
		)
		(fp_line
			(start 0.12065 -0.2794)
			(end -0.12065 -0.2794)
			(stroke
				(width 0.1)
				(type default)
			)
			(layer "B.Fab")
		)
		(fp_line
			(start -0.12065 -0.2794)
			(end -0.12065 -0.3048)
			(stroke
				(width 0.1)
				(type default)
			)
			(layer "B.Fab")
		)
		(fp_line
			(start 0.12065 0.2794)
			(end 0.12065 0.3048)
			(stroke
				(width 0.1)
				(type default)
			)
			(layer "B.Fab")
		)
		(fp_line
			(start -0.120396 0.2794)
			(end 0.12065 0.2794)
			(stroke
				(width 0.1)
				(type default)
			)
			(layer "B.Fab")
		)
		(fp_line
			(start 0.67945 0.3048)
			(end 0.67945 -0.305054)
			(stroke
				(width 0.1)
				(type default)
			)
			(layer "B.Fab")
		)
		(fp_line
			(start 0.12065 0.3048)
			(end 0.67945 0.3048)
			(stroke
				(width 0.1)
				(type default)
			)
			(layer "B.Fab")
		)
		(fp_line
			(start -0.120396 0.3048)
			(end -0.120396 0.2794)
			(stroke
				(width 0.1)
				(type default)
			)
			(layer "B.Fab")
		)
		(fp_line
			(start -0.67945 0.3048)
			(end -0.120396 0.3048)
			(stroke
				(width 0.1)
				(type default)
			)
			(layer "B.Fab")
		)
		(pad "1" smd circle
			(at 0.40005 0 270)
			(size 0 0)
			(layers "B.Cu" "B.Mask" "B.Paste")
			(net "PVDD11_S3_P0")
		)
		(pad "2" smd circle
			(at -0.40005 0 270)
			(size 0 0)
			(layers "B.Cu" "B.Mask" "B.Paste")
			(net "GND")
		)
	)
	(footprint ""
		(layer "B.Cu")
		(at 171.195492 -102.780084 180)
		(property "Reference" "R6147"
			(at 0 0 0)
			(layer "B.SilkS")
			(hide yes)
			(effects
				(font
					(size 1.27 1.27)
				)
				(justify mirror)
			)
		)
		(property "Value" ""
			(at 0 0 0)
			(layer "B.Fab")
			(effects
				(font
					(size 1.27 1.27)
				)
				(justify mirror)
			)
		)
		(duplicate_pad_numbers_are_jumpers no)
		(fp_line
			(start 0.7874 0.4064)
			(end 0.7874 -0.4064)
			(stroke
				(width 0.1524)
				(type default)
			)
			(layer "B.SilkS")
		)
		(fp_line
			(start 0.7874 -0.4064)
			(end -0.7874 -0.4064)
			(stroke
				(width 0.1524)
				(type default)
			)
			(layer "B.SilkS")
		)
		(fp_line
			(start -0.7874 0.4064)
			(end 0.7874 0.4064)
			(stroke
				(width 0.1524)
				(type default)
			)
			(layer "B.SilkS")
		)
		(fp_line
			(start -0.7874 -0.4064)
			(end -0.7874 0.4064)
			(stroke
				(width 0.1524)
				(type default)
			)
			(layer "B.SilkS")
		)
		(fp_line
			(start 0.67945 0.3048)
			(end 0.67945 -0.305054)
			(stroke
				(width 0.1)
				(type default)
			)
			(layer "B.Fab")
		)
		(fp_line
			(start 0.67945 -0.305054)
			(end 0.12065 -0.305054)
			(stroke
				(width 0.1)
				(type default)
			)
			(layer "B.Fab")
		)
		(fp_line
			(start 0.12065 0.3048)
			(end 0.67945 0.3048)
			(stroke
				(width 0.1)
				(type default)
			)
			(layer "B.Fab")
		)
		(fp_line
			(start 0.12065 0.2794)
			(end 0.12065 0.3048)
			(stroke
				(width 0.1)
				(type default)
			)
			(layer "B.Fab")
		)
		(fp_line
			(start 0.12065 -0.2794)
			(end -0.12065 -0.2794)
			(stroke
				(width 0.1)
				(type default)
			)
			(layer "B.Fab")
		)
		(fp_line
			(start 0.12065 -0.305054)
			(end 0.12065 -0.2794)
			(stroke
				(width 0.1)
				(type default)
			)
			(layer "B.Fab")
		)
		(fp_line
			(start -0.120396 0.3048)
			(end -0.120396 0.2794)
			(stroke
				(width 0.1)
				(type default)
			)
			(layer "B.Fab")
		)
		(fp_line
			(start -0.120396 0.2794)
			(end 0.12065 0.2794)
			(stroke
				(width 0.1)
				(type default)
			)
			(layer "B.Fab")
		)
		(fp_line
			(start -0.12065 -0.2794)
			(end -0.12065 -0.3048)
			(stroke
				(width 0.1)
				(type default)
			)
			(layer "B.Fab")
		)
		(fp_line
			(start -0.12065 -0.3048)
			(end -0.67945 -0.3048)
			(stroke
				(width 0.1)
				(type default)
			)
			(layer "B.Fab")
		)
		(fp_line
			(start -0.67945 0.3048)
			(end -0.120396 0.3048)
			(stroke
				(width 0.1)
				(type default)
			)
			(layer "B.Fab")
		)
		(fp_line
			(start -0.67945 -0.3048)
			(end -0.67945 0.3048)
			(stroke
				(width 0.1)
				(type default)
			)
			(layer "B.Fab")
		)
		(pad "1" smd circle
			(at 0.40005 0)
			(size 0 0)
			(layers "B.Cu" "B.Mask" "B.Paste")
			(net "P1V8_AUX")
		)
		(pad "2" smd circle
			(at -0.40005 0)
			(size 0 0)
			(layers "B.Cu" "B.Mask" "B.Paste")
			(net "FAB_BMC_REV_ID1")
		)
	)
	(footprint ""
		(layer "B.Cu")
		(at 329.459082 -326.30745 -90)
		(property "Reference" "PC106_2"
			(at 0 0 90)
			(layer "B.SilkS")
			(hide yes)
			(effects
				(font
					(size 1.27 1.27)
				)
				(justify mirror)
			)
		)
		(property "Value" ""
			(at 0 0 90)
			(layer "B.Fab")
			(effects
				(font
					(size 1.27 1.27)
				)
				(justify mirror)
			)
		)
		(duplicate_pad_numbers_are_jumpers no)
		(fp_line
			(start -1.524 0.762)
			(end 1.524 0.762)
			(stroke
				(width 0.1524)
				(type default)
			)
			(layer "B.SilkS")
		)
		(fp_line
			(start 1.524 0.762)
			(end 1.524 -0.762)
			(stroke
				(width 0.1524)
				(type default)
			)
			(layer "B.SilkS")
		)
		(fp_line
			(start -1.524 -0.762)
			(end -1.524 0.762)
			(stroke
				(width 0.1524)
				(type default)
			)
			(layer "B.SilkS")
		)
		(fp_line
			(start 1.524 -0.762)
			(end -1.524 -0.762)
			(stroke
				(width 0.1524)
				(type default)
			)
			(layer "B.SilkS")
		)
		(fp_line
			(start -1.1049 0.724916)
			(end -1.1049 -0.724916)
			(stroke
				(width 0.1)
				(type default)
			)
			(layer "B.Fab")
		)
		(fp_line
			(start 1.1049 0.724916)
			(end -1.1049 0.724916)
			(stroke
				(width 0.1)
				(type default)
			)
			(layer "B.Fab")
		)
		(fp_line
			(start -1.1049 -0.724916)
			(end 1.1049 -0.724916)
			(stroke
				(width 0.1)
				(type default)
			)
			(layer "B.Fab")
		)
		(fp_line
			(start 1.1049 -0.724916)
			(end 1.1049 0.724916)
			(stroke
				(width 0.1)
				(type default)
			)
			(layer "B.Fab")
		)
		(pad "1" smd rect
			(at 0.889 0 270)
			(size 1.016 1.27)
			(layers "B.Cu" "B.Mask" "B.Paste")
			(net "PVDDCR_CPU1_P0")
		)
		(pad "2" smd rect
			(at -0.889 0 270)
			(size 1.016 1.27)
			(layers "B.Cu" "B.Mask" "B.Paste")
			(net "GND")
		)
	)
)
